(kicad_pcb
	(version 20260206)
	(generator "pcbnew")
	(generator_version "10.0")
	(general
		(thickness 1.6)
		(legacy_teardrops no)
	)
	(paper "A4")
	(title_block
		(title "baseboard — 13948-1b.1110WZS1818.brd")
		(comment 1 "Honey Badger (Wiwynn) / footprints 302-309 of 2523")
	)
	(layers
		(0 "F.Cu" signal "TOP")
		(4 "In1.Cu" signal "L2GND")
		(6 "In2.Cu" signal "L3")
		(8 "In3.Cu" signal "L4VCC")
		(10 "In4.Cu" signal "L5VCC")
		(12 "In5.Cu" signal "L6")
		(14 "In6.Cu" signal "L7GND")
		(2 "B.Cu" signal "BOTTOM")
		(9 "F.Adhes" user "F.Adhesive")
		(11 "B.Adhes" user "B.Adhesive")
		(13 "F.Paste" user "Package Geometry/Pastemask Top")
		(15 "B.Paste" user "Package Geometry/Pastemask Bottom")
		(5 "F.SilkS" user "Ref Des/Silkscreen Top")
		(7 "B.SilkS" user "Ref Des/Silkscreen Bottom")
		(1 "F.Mask" user "Board Geometry/Soldermask Top")
		(3 "B.Mask" user "Board Geometry/Soldermask Bottom")
		(17 "Dwgs.User" user "User.Drawings")
		(19 "Cmts.User" user "User.Comments")
		(21 "Eco1.User" user "User.Eco1")
		(23 "Eco2.User" user "User.Eco2")
		(25 "Edge.Cuts" user "Board Geometry/Outline")
		(27 "Margin" user)
		(31 "F.CrtYd" user "Package Geometry/Place Bound Top")
		(29 "B.CrtYd" user "Package Geometry/Place Bound Bottom")
		(35 "F.Fab" user "Ref Des/Assembly Top")
		(33 "B.Fab" user "Ref Des/Assembly Bottom")
	)
	(footprint ""
		(layer "F.Cu")
		(at 328.667872 -167.966136)
		(property "Reference" "R323"
			(at 0 0 0)
			(layer "F.SilkS")
			(hide yes)
			(effects
				(font
					(size 1.27 1.27)
				)
			)
		)
		(property "Value" "0R2J-2-GP"
			(at 0.064008 -3.993896 0)
			(unlocked yes)
			(layer "F.Fab")
			(hide yes)
			(effects
				(font
					(size 1.016 1.016)
					(thickness 0.1524)
				)
			)
		)
		(property "Device Type" "R402H16"
			(at 0.064008 -5.517896 0)
			(unlocked yes)
			(layer "F.Fab")
			(hide yes)
			(effects
				(font
					(size 1.016 1.016)
					(thickness 0.1524)
				)
			)
		)
		(duplicate_pad_numbers_are_jumpers no)
		(fp_line
			(start -0.508 -0.9398)
			(end -0.508 0.9398)
			(stroke
				(width 0.1524)
				(type default)
			)
			(layer "F.SilkS")
		)
		(fp_line
			(start 0.508 -0.9398)
			(end -0.508 -0.9398)
			(stroke
				(width 0.1524)
				(type default)
			)
			(layer "F.SilkS")
		)
		(fp_rect
			(start -0.508 0.9398)
			(end 0.508 -0.9398)
			(stroke
				(width 0)
				(type default)
			)
			(fill no)
			(layer "F.CrtYd")
		)
		(fp_rect
			(start -0.508 0.9398)
			(end 0.508 -0.9398)
			(stroke
				(width 0)
				(type default)
			)
			(fill no)
			(layer "F.Fab")
		)
		(pad "1" smd custom
			(at 0 -0.4445)
			(size 0.1397 0.1397)
			(layers "F.Cu" "F.Mask" "F.Paste")
			(net "CPU_S_RXD")
			(options
				(clearance outline)
				(anchor circle)
			)
			(primitives
				(gr_poly
					(pts
						(arc
							(start -0.1778 -0.2794)
							(mid -0.249642 -0.249642)
							(end -0.2794 -0.1778)
						)
						(arc
							(start -0.2794 0.1778)
							(mid -0.249642 0.249642)
							(end -0.1778 0.2794)
						)
						(arc
							(start 0.1778 0.2794)
							(mid 0.249642 0.249642)
							(end 0.2794 0.1778)
						)
						(arc
							(start 0.2794 -0.1778)
							(mid 0.249642 -0.249642)
							(end 0.1778 -0.2794)
						)
					)
					(width 0)
					(fill yes)
				)
			)
		)
		(pad "2" smd custom
			(at 0 0.4445)
			(size 0.1397 0.1397)
			(layers "F.Cu" "F.Mask" "F.Paste")
			(net "CPU_UART_RX_R")
			(options
				(clearance outline)
				(anchor circle)
			)
			(primitives
				(gr_poly
					(pts
						(arc
							(start -0.1778 -0.2794)
							(mid -0.249642 -0.249642)
							(end -0.2794 -0.1778)
						)
						(arc
							(start -0.2794 0.1778)
							(mid -0.249642 0.249642)
							(end -0.1778 0.2794)
						)
						(arc
							(start 0.1778 0.2794)
							(mid 0.249642 0.249642)
							(end 0.2794 0.1778)
						)
						(arc
							(start 0.2794 -0.1778)
							(mid 0.249642 -0.249642)
							(end 0.1778 -0.2794)
						)
					)
					(width 0)
					(fill yes)
				)
			)
		)
	)
	(footprint ""
		(layer "F.Cu")
		(at 316.484 -193.548 -90)
		(property "Reference" "R799"
			(at 0 0 270)
			(layer "F.SilkS")
			(hide yes)
			(effects
				(font
					(size 1.27 1.27)
				)
			)
		)
		(property "Value" "4K7R2F-GP"
			(at 0.064008 -3.993896 270)
			(unlocked yes)
			(layer "F.Fab")
			(hide yes)
			(effects
				(font
					(size 1.016 1.016)
					(thickness 0.1524)
				)
			)
		)
		(property "Device Type" "R402H16"
			(at 0.064008 -5.517896 270)
			(unlocked yes)
			(layer "F.Fab")
			(hide yes)
			(effects
				(font
					(size 1.016 1.016)
					(thickness 0.1524)
				)
			)
		)
		(duplicate_pad_numbers_are_jumpers no)
		(fp_line
			(start -0.508 -0.9398)
			(end -0.508 0.9398)
			(stroke
				(width 0.1524)
				(type default)
			)
			(layer "F.SilkS")
		)
		(fp_line
			(start 0.508 -0.9398)
			(end -0.508 -0.9398)
			(stroke
				(width 0.1524)
				(type default)
			)
			(layer "F.SilkS")
		)
		(fp_rect
			(start -0.508 0.9398)
			(end 0.508 -0.9398)
			(stroke
				(width 0)
				(type default)
			)
			(fill no)
			(layer "F.CrtYd")
		)
		(fp_rect
			(start -0.508 0.9398)
			(end 0.508 -0.9398)
			(stroke
				(width 0)
				(type default)
			)
			(fill no)
			(layer "F.Fab")
		)
		(pad "1" smd custom
			(at 0 -0.4445 270)
			(size 0.1397 0.1397)
			(layers "F.Cu" "F.Mask" "F.Paste")
			(net "P3V3_STBY")
			(options
				(clearance outline)
				(anchor circle)
			)
			(primitives
				(gr_poly
					(pts
						(arc
							(start -0.1778 -0.2794)
							(mid -0.249642 -0.249642)
							(end -0.2794 -0.1778)
						)
						(arc
							(start -0.2794 0.1778)
							(mid -0.249642 0.249642)
							(end -0.1778 0.2794)
						)
						(arc
							(start 0.1778 0.2794)
							(mid 0.249642 0.249642)
							(end 0.2794 0.1778)
						)
						(arc
							(start 0.2794 -0.1778)
							(mid 0.249642 -0.249642)
							(end 0.1778 -0.2794)
						)
					)
					(width 0)
					(fill yes)
				)
			)
		)
		(pad "2" smd custom
			(at 0 0.4445 270)
			(size 0.1397 0.1397)
			(layers "F.Cu" "F.Mask" "F.Paste")
			(net "JTAG_BMC_TDO")
			(options
				(clearance outline)
				(anchor circle)
			)
			(primitives
				(gr_poly
					(pts
						(arc
							(start -0.1778 -0.2794)
							(mid -0.249642 -0.249642)
							(end -0.2794 -0.1778)
						)
						(arc
							(start -0.2794 0.1778)
							(mid -0.249642 0.249642)
							(end -0.1778 0.2794)
						)
						(arc
							(start 0.1778 0.2794)
							(mid 0.249642 0.249642)
							(end 0.2794 0.1778)
						)
						(arc
							(start 0.2794 -0.1778)
							(mid 0.249642 -0.249642)
							(end 0.1778 -0.2794)
						)
					)
					(width 0)
					(fill yes)
				)
			)
		)
	)
	(footprint ""
		(layer "F.Cu")
		(at 209.042 -221.742 -90)
		(property "Reference" "R686"
			(at 0 0 270)
			(layer "F.SilkS")
			(hide yes)
			(effects
				(font
					(size 1.27 1.27)
				)
			)
		)
		(property "Value" "0R2J-2-GP"
			(at 0.064008 -3.993896 270)
			(unlocked yes)
			(layer "F.Fab")
			(hide yes)
			(effects
				(font
					(size 1.016 1.016)
					(thickness 0.1524)
				)
			)
		)
		(property "Device Type" "R402H16"
			(at 0.064008 -5.517896 270)
			(unlocked yes)
			(layer "F.Fab")
			(hide yes)
			(effects
				(font
					(size 1.016 1.016)
					(thickness 0.1524)
				)
			)
		)
		(duplicate_pad_numbers_are_jumpers no)
		(fp_line
			(start -0.508 -0.9398)
			(end -0.508 0.9398)
			(stroke
				(width 0.1524)
				(type default)
			)
			(layer "F.SilkS")
		)
		(fp_line
			(start 0.508 -0.9398)
			(end -0.508 -0.9398)
			(stroke
				(width 0.1524)
				(type default)
			)
			(layer "F.SilkS")
		)
		(fp_rect
			(start -0.508 0.9398)
			(end 0.508 -0.9398)
			(stroke
				(width 0)
				(type default)
			)
			(fill no)
			(layer "F.CrtYd")
		)
		(fp_rect
			(start -0.508 0.9398)
			(end 0.508 -0.9398)
			(stroke
				(width 0)
				(type default)
			)
			(fill no)
			(layer "F.Fab")
		)
		(pad "1" smd custom
			(at 0 -0.4445 270)
			(size 0.1397 0.1397)
			(layers "F.Cu" "F.Mask" "F.Paste")
			(net "OE_BMC_RSET")
			(options
				(clearance outline)
				(anchor circle)
			)
			(primitives
				(gr_poly
					(pts
						(arc
							(start -0.1778 -0.2794)
							(mid -0.249642 -0.249642)
							(end -0.2794 -0.1778)
						)
						(arc
							(start -0.2794 0.1778)
							(mid -0.249642 0.249642)
							(end -0.1778 0.2794)
						)
						(arc
							(start 0.1778 0.2794)
							(mid 0.249642 0.249642)
							(end 0.2794 0.1778)
						)
						(arc
							(start 0.2794 -0.1778)
							(mid 0.249642 -0.249642)
							(end 0.1778 -0.2794)
						)
					)
					(width 0)
					(fill yes)
				)
			)
		)
		(pad "2" smd custom
			(at 0 0.4445 270)
			(size 0.1397 0.1397)
			(layers "F.Cu" "F.Mask" "F.Paste")
			(net "BMC_EN_CPU_RESET_CONTROL")
			(options
				(clearance outline)
				(anchor circle)
			)
			(primitives
				(gr_poly
					(pts
						(arc
							(start -0.1778 -0.2794)
							(mid -0.249642 -0.249642)
							(end -0.2794 -0.1778)
						)
						(arc
							(start -0.2794 0.1778)
							(mid -0.249642 0.249642)
							(end -0.1778 0.2794)
						)
						(arc
							(start 0.1778 0.2794)
							(mid 0.249642 0.249642)
							(end 0.2794 0.1778)
						)
						(arc
							(start 0.2794 -0.1778)
							(mid 0.249642 -0.249642)
							(end 0.1778 -0.2794)
						)
					)
					(width 0)
					(fill yes)
				)
			)
		)
	)
	(footprint ""
		(layer "F.Cu")
		(at 300.736 -191.897)
		(property "Reference" "R584"
			(at 0 0 0)
			(layer "F.SilkS")
			(hide yes)
			(effects
				(font
					(size 1.27 1.27)
				)
			)
		)
		(property "Value" "0R2J-2-GP"
			(at 0.064008 -3.993896 0)
			(unlocked yes)
			(layer "F.Fab")
			(hide yes)
			(effects
				(font
					(size 1.016 1.016)
					(thickness 0.1524)
				)
			)
		)
		(property "Device Type" "R402H16"
			(at 0.064008 -5.517896 0)
			(unlocked yes)
			(layer "F.Fab")
			(hide yes)
			(effects
				(font
					(size 1.016 1.016)
					(thickness 0.1524)
				)
			)
		)
		(duplicate_pad_numbers_are_jumpers no)
		(fp_line
			(start -0.508 -0.9398)
			(end -0.508 0.9398)
			(stroke
				(width 0.1524)
				(type default)
			)
			(layer "F.SilkS")
		)
		(fp_line
			(start 0.508 -0.9398)
			(end -0.508 -0.9398)
			(stroke
				(width 0.1524)
				(type default)
			)
			(layer "F.SilkS")
		)
		(fp_rect
			(start -0.508 0.9398)
			(end 0.508 -0.9398)
			(stroke
				(width 0)
				(type default)
			)
			(fill no)
			(layer "F.CrtYd")
		)
		(fp_rect
			(start -0.508 0.9398)
			(end 0.508 -0.9398)
			(stroke
				(width 0)
				(type default)
			)
			(fill no)
			(layer "F.Fab")
		)
		(pad "1" smd custom
			(at 0 -0.4445)
			(size 0.1397 0.1397)
			(layers "F.Cu" "F.Mask" "F.Paste")
			(net "UART COUNT")
			(options
				(clearance outline)
				(anchor circle)
			)
			(primitives
				(gr_poly
					(pts
						(arc
							(start -0.1778 -0.2794)
							(mid -0.249642 -0.249642)
							(end -0.2794 -0.1778)
						)
						(arc
							(start -0.2794 0.1778)
							(mid -0.249642 0.249642)
							(end -0.1778 0.2794)
						)
						(arc
							(start 0.1778 0.2794)
							(mid 0.249642 0.249642)
							(end 0.2794 0.1778)
						)
						(arc
							(start 0.2794 -0.1778)
							(mid 0.249642 -0.249642)
							(end 0.1778 -0.2794)
						)
					)
					(width 0)
					(fill yes)
				)
			)
		)
		(pad "2" smd custom
			(at 0 0.4445)
			(size 0.1397 0.1397)
			(layers "F.Cu" "F.Mask" "F.Paste")
			(net "BMC0_TACH13")
			(options
				(clearance outline)
				(anchor circle)
			)
			(primitives
				(gr_poly
					(pts
						(arc
							(start -0.1778 -0.2794)
							(mid -0.249642 -0.249642)
							(end -0.2794 -0.1778)
						)
						(arc
							(start -0.2794 0.1778)
							(mid -0.249642 0.249642)
							(end -0.1778 0.2794)
						)
						(arc
							(start 0.1778 0.2794)
							(mid 0.249642 0.249642)
							(end 0.2794 0.1778)
						)
						(arc
							(start 0.2794 -0.1778)
							(mid 0.249642 -0.249642)
							(end 0.1778 -0.2794)
						)
					)
					(width 0)
					(fill yes)
				)
			)
		)
	)
	(footprint ""
		(layer "F.Cu")
		(at 301.371 -152.146 180)
		(property "Reference" "R528"
			(at 0 0 180)
			(layer "F.SilkS")
			(hide yes)
			(effects
				(font
					(size 1.27 1.27)
				)
			)
		)
		(property "Value" "33R2J-2-GP"
			(at 0.064008 -3.993896 180)
			(unlocked yes)
			(layer "F.Fab")
			(hide yes)
			(effects
				(font
					(size 1.016 1.016)
					(thickness 0.1524)
				)
			)
		)
		(property "Device Type" "R402H16"
			(at 0.064008 -5.517896 180)
			(unlocked yes)
			(layer "F.Fab")
			(hide yes)
			(effects
				(font
					(size 1.016 1.016)
					(thickness 0.1524)
				)
			)
		)
		(duplicate_pad_numbers_are_jumpers no)
		(fp_line
			(start 0.508 -0.9398)
			(end -0.508 -0.9398)
			(stroke
				(width 0.1524)
				(type default)
			)
			(layer "F.SilkS")
		)
		(fp_line
			(start -0.508 -0.9398)
			(end -0.508 0.9398)
			(stroke
				(width 0.1524)
				(type default)
			)
			(layer "F.SilkS")
		)
		(fp_rect
			(start -0.508 0.9398)
			(end 0.508 -0.9398)
			(stroke
				(width 0)
				(type default)
			)
			(fill no)
			(layer "F.CrtYd")
		)
		(fp_rect
			(start -0.508 0.9398)
			(end 0.508 -0.9398)
			(stroke
				(width 0)
				(type default)
			)
			(fill no)
			(layer "F.Fab")
		)
		(pad "1" smd custom
			(at 0 -0.4445 180)
			(size 0.1397 0.1397)
			(layers "F.Cu" "F.Mask" "F.Paste")
			(net "50M_CLK_OUT")
			(options
				(clearance outline)
				(anchor circle)
			)
			(primitives
				(gr_poly
					(pts
						(arc
							(start -0.1778 -0.2794)
							(mid -0.249642 -0.249642)
							(end -0.2794 -0.1778)
						)
						(arc
							(start -0.2794 0.1778)
							(mid -0.249642 0.249642)
							(end -0.1778 0.2794)
						)
						(arc
							(start 0.1778 0.2794)
							(mid 0.249642 0.249642)
							(end 0.2794 0.1778)
						)
						(arc
							(start 0.2794 -0.1778)
							(mid 0.249642 -0.249642)
							(end 0.1778 -0.2794)
						)
					)
					(width 0)
					(fill yes)
				)
			)
		)
		(pad "2" smd custom
			(at 0 0.4445 180)
			(size 0.1397 0.1397)
			(layers "F.Cu" "F.Mask" "F.Paste")
			(net "50M_CLK_OUT_R")
			(options
				(clearance outline)
				(anchor circle)
			)
			(primitives
				(gr_poly
					(pts
						(arc
							(start -0.1778 -0.2794)
							(mid -0.249642 -0.249642)
							(end -0.2794 -0.1778)
						)
						(arc
							(start -0.2794 0.1778)
							(mid -0.249642 0.249642)
							(end -0.1778 0.2794)
						)
						(arc
							(start 0.1778 0.2794)
							(mid 0.249642 0.249642)
							(end 0.2794 0.1778)
						)
						(arc
							(start 0.2794 -0.1778)
							(mid 0.249642 -0.249642)
							(end 0.1778 -0.2794)
						)
					)
					(width 0)
					(fill yes)
				)
			)
		)
	)
	(footprint ""
		(layer "F.Cu")
		(at 52.08397 -137.795 90)
		(property "Reference" "SU80"
			(at 0 0 90)
			(layer "F.SilkS")
			(hide yes)
			(effects
				(font
					(size 1.27 1.27)
				)
			)
		)
		(property "Value" "SN74LVC1G08DCKR-GP"
			(at -2.3368 -8.6868 90)
			(unlocked yes)
			(layer "F.Fab")
			(hide yes)
			(effects
				(font
					(size 1.016 1.016)
					(thickness 0.1524)
				)
			)
		)
		(property "Device Type" "SC70-5H44"
			(at -2.3114 -10.414 90)
			(unlocked yes)
			(layer "F.Fab")
			(hide yes)
			(effects
				(font
					(size 1.016 1.016)
					(thickness 0.1524)
				)
			)
		)
		(duplicate_pad_numbers_are_jumpers no)
		(fp_line
			(start 1.3843 -1.8034)
			(end 1.3843 -1.1176)
			(stroke
				(width 0.3302)
				(type default)
			)
			(layer "F.SilkS")
		)
		(fp_line
			(start 0.6604 -1.8034)
			(end 1.3843 -1.8034)
			(stroke
				(width 0.3302)
				(type default)
			)
			(layer "F.SilkS")
		)
		(fp_line
			(start 1.27 -1.7018)
			(end 1.27 1.7018)
			(stroke
				(width 0.1524)
				(type default)
			)
			(layer "F.SilkS")
		)
		(fp_line
			(start -1.27 -1.7018)
			(end 1.27 -1.7018)
			(stroke
				(width 0.1524)
				(type default)
			)
			(layer "F.SilkS")
		)
		(fp_line
			(start 1.27 1.7018)
			(end -1.27 1.7018)
			(stroke
				(width 0.1524)
				(type default)
			)
			(layer "F.SilkS")
		)
		(fp_line
			(start -1.27 1.7018)
			(end -1.27 -1.7018)
			(stroke
				(width 0.1524)
				(type default)
			)
			(layer "F.SilkS")
		)
		(fp_rect
			(start -1.524 1.9558)
			(end 1.524 -1.9558)
			(stroke
				(width 0)
				(type default)
			)
			(fill no)
			(layer "F.CrtYd")
		)
		(fp_poly
			(pts
				(xy -1.524 -1.9558) (xy 1.524 -1.9558) (xy 1.524 1.9558) (xy -1.524 1.9558)
			)
			(stroke
				(width 0)
				(type default)
			)
			(fill no)
			(layer "F.Fab")
		)
		(pad "1" smd rect
			(at 0.65024 -0.8255 90)
			(size 0.4064 1.2192)
			(layers "F.Cu" "F.Mask" "F.Paste")
			(net "EXP_RST_1")
		)
		(pad "2" smd rect
			(at 0 -0.8255 90)
			(size 0.4064 1.2192)
			(layers "F.Cu" "F.Mask" "F.Paste")
			(net "EXP_RST_2")
		)
		(pad "3" smd rect
			(at -0.65024 -0.8255 90)
			(size 0.4064 1.2192)
			(layers "F.Cu" "F.Mask" "F.Paste")
			(net "GND")
		)
		(pad "4" smd rect
			(at -0.65024 0.8255 90)
			(size 0.4064 1.2192)
			(layers "F.Cu" "F.Mask" "F.Paste")
			(net "RESET_N")
		)
		(pad "5" smd rect
			(at 0.65024 0.8255 90)
			(size 0.4064 1.2192)
			(layers "F.Cu" "F.Mask" "F.Paste")
			(net "P1V8_E")
		)
	)
	(footprint ""
		(layer "F.Cu")
		(at 163.417504 -24.184356 180)
		(property "Reference" "R418"
			(at 0 0 180)
			(layer "F.SilkS")
			(hide yes)
			(effects
				(font
					(size 1.27 1.27)
				)
			)
		)
		(property "Value" "0R2J-2-GP"
			(at 0.064008 -3.993896 180)
			(unlocked yes)
			(layer "F.Fab")
			(hide yes)
			(effects
				(font
					(size 1.016 1.016)
					(thickness 0.1524)
				)
			)
		)
		(property "Device Type" "R402H16"
			(at 0.064008 -5.517896 180)
			(unlocked yes)
			(layer "F.Fab")
			(hide yes)
			(effects
				(font
					(size 1.016 1.016)
					(thickness 0.1524)
				)
			)
		)
		(duplicate_pad_numbers_are_jumpers no)
		(fp_line
			(start 0.508 -0.9398)
			(end -0.508 -0.9398)
			(stroke
				(width 0.1524)
				(type default)
			)
			(layer "F.SilkS")
		)
		(fp_line
			(start -0.508 -0.9398)
			(end -0.508 0.9398)
			(stroke
				(width 0.1524)
				(type default)
			)
			(layer "F.SilkS")
		)
		(fp_rect
			(start -0.508 0.9398)
			(end 0.508 -0.9398)
			(stroke
				(width 0)
				(type default)
			)
			(fill no)
			(layer "F.CrtYd")
		)
		(fp_rect
			(start -0.508 0.9398)
			(end 0.508 -0.9398)
			(stroke
				(width 0)
				(type default)
			)
			(fill no)
			(layer "F.Fab")
		)
		(pad "1" smd custom
			(at 0 -0.4445 180)
			(size 0.1397 0.1397)
			(layers "F.Cu" "F.Mask" "F.Paste")
			(net "TP_LAN_6")
			(options
				(clearance outline)
				(anchor circle)
			)
			(primitives
				(gr_poly
					(pts
						(arc
							(start -0.1778 -0.2794)
							(mid -0.249642 -0.249642)
							(end -0.2794 -0.1778)
						)
						(arc
							(start -0.2794 0.1778)
							(mid -0.249642 0.249642)
							(end -0.1778 0.2794)
						)
						(arc
							(start 0.1778 0.2794)
							(mid 0.249642 0.249642)
							(end 0.2794 0.1778)
						)
						(arc
							(start 0.2794 -0.1778)
							(mid 0.249642 -0.249642)
							(end 0.1778 -0.2794)
						)
					)
					(width 0)
					(fill yes)
				)
			)
		)
		(pad "2" smd custom
			(at 0 0.4445 180)
			(size 0.1397 0.1397)
			(layers "F.Cu" "F.Mask" "F.Paste")
			(net "GND")
			(options
				(clearance outline)
				(anchor circle)
			)
			(primitives
				(gr_poly
					(pts
						(arc
							(start -0.1778 -0.2794)
							(mid -0.249642 -0.249642)
							(end -0.2794 -0.1778)
						)
						(arc
							(start -0.2794 0.1778)
							(mid -0.249642 0.249642)
							(end -0.1778 0.2794)
						)
						(arc
							(start 0.1778 0.2794)
							(mid 0.249642 0.249642)
							(end 0.2794 0.1778)
						)
						(arc
							(start 0.2794 -0.1778)
							(mid 0.249642 -0.249642)
							(end 0.1778 -0.2794)
						)
					)
					(width 0)
					(fill yes)
				)
			)
		)
	)
	(footprint ""
		(layer "F.Cu")
		(at 175.90897 -67.945)
		(property "Reference" "TP157"
			(at 0 0 0)
			(layer "F.SilkS")
			(hide yes)
			(effects
				(font
					(size 1.27 1.27)
				)
			)
		)
		(property "Value" "TPAD28"
			(at 0.0127 -1.8034 0)
			(unlocked yes)
			(layer "F.Fab")
			(hide yes)
			(effects
				(font
					(size 1.016 1.016)
					(thickness 0.1524)
				)
			)
		)
		(property "Device Type" "TPAD28"
			(at 0.0127 -3.3274 0)
			(unlocked yes)
			(layer "F.Fab")
			(hide yes)
			(effects
				(font
					(size 1.016 1.016)
					(thickness 0.1524)
				)
			)
		)
		(duplicate_pad_numbers_are_jumpers no)
		(fp_poly
			(pts
				(arc
					(start 0.3556 0)
					(mid -0.3556 0)
					(end 0.3556 0)
				)
			)
			(stroke
				(width 0)
				(type default)
			)
			(fill no)
			(layer "F.CrtYd")
		)
		(fp_poly
			(pts
				(arc
					(start 0.6096 0)
					(mid -0.6096 0)
					(end 0.6096 0)
				)
			)
			(stroke
				(width 0)
				(type default)
			)
			(fill no)
			(layer "F.Fab")
		)
		(pad "1" smd circle
			(at 0 0)
			(size 0.7112 0.7112)
			(layers "F.Cu" "F.Mask" "F.Paste")
			(net "TP_MSB_B40")
		)
	)
)
